FILE_TYPE = MACRO_DRAWING;
SET COLOR_WIRE YELLOW;
SET COLOR_PROP ORANGE;
SET COLOR_DOT WHITE;
SET COLOR_ARC YELLOW;
SET COLOR_BODY GREEN;
SET COLOR_NOTE PURPLE;
SET PROP_DISPLAY VALUE;
SET PAGE_NUMBER P142;
FORCEADD Q_LED..1
(-4650 1575);
FORCEPROP 1 LAST LOCATION D9
J 0
(-4750 1760);
DISPLAY 0.489362 (-4750 1760);
PAINT SKYBLUE (-4750 1760);
FORCEPROP 0 LAST $SEC 1
J 0
(-4750 1800);
DISPLAY 0.680851 (-4750 1800);
PAINT MONO (-4750 1800);
DISPLAY INVISIBLE (-4750 1800);
FORCEPROP 0 LAST CDS_SEC 1
J 0
(-4750 1800);
DISPLAY 0.680851 (-4750 1800);
DISPLAY INVISIBLE (-4750 1800);
FORCEPROP 0 LASTPIN (-4800 1575) $PN A
J 2
(-4810 1585);
DISPLAY 0.489362 (-4810 1585);
PAINT MONO (-4810 1585);
FORCEPROP 0 LASTPIN (-4500 1575) $PN C
J 0
(-4490 1585);
DISPLAY 0.489362 (-4490 1585);
PAINT MONO (-4490 1585);
FORCEPROP 2 LAST MANUF_PN 19-213/GVC-AMNB/3T
J 0
(-4825 1425);
DISPLAY 0.680851 (-4825 1425);
FORCEPROP 1 LAST MATERIAL IC
J 0
(-4750 1655);
DISPLAY 0.489362 (-4750 1655);
PAINT SKYBLUE (-4750 1655);
FORCEPROP 1 LAST PART_NUMBER BEGR0278Z00
J 0
(-4750 1710);
DISPLAY 0.489362 (-4750 1710);
PAINT SKYBLUE (-4750 1710);
FORCEPROP 2 LAST COLOR LED_GREEN
J 0
(-4825 1375);
DISPLAY 0.489362 (-4825 1375);
FORCEPROP 2 LAST PACK_TYPE SMLF
J 0
(-4825 1475);
DISPLAY 0.489362 (-4825 1475);
PAINT SKYBLUE (-4825 1475);
FORCEPROP 2 LAST CDS_LIB pure_quanta
J 2
(-4650 1575);
DISPLAY INVISIBLE (-4650 1575);
FORCEPROP 1 LAST NEEDS_NO_SIZE TRUE
J 0
(-4650 1575);
DISPLAY 0.468085 (-4650 1575);
PAINT GREEN (-4650 1575);
DISPLAY INVISIBLE (-4650 1575);
FORCEPROP 1 LAST PATH I79
J 0
(-4525 1655);
DISPLAY 0.723404 (-4525 1655);
PAINT GREEN (-4525 1655);
DISPLAY INVISIBLE (-4525 1655);
FORCEADD MOSFET_N_GSD..1
R 2
(-3550 1300);
FORCEPROP 1 LAST LOCATION Q29
J 2
(-3651 1345);
DISPLAY 0.489362 (-3651 1345);
PAINT SKYBLUE (-3651 1345);
FORCEPROP 0 LAST $SEC 1
J 0
(-3650 1525);
DISPLAY 0.680851 (-3650 1525);
PAINT MONO (-3650 1525);
DISPLAY INVISIBLE (-3650 1525);
FORCEPROP 0 LAST CDS_SEC 1
J 0
(-3650 1525);
DISPLAY 0.680851 (-3650 1525);
DISPLAY INVISIBLE (-3650 1525);
FORCEPROP 0 LASTPIN (-3575 1450) $PN D
R 1
J 0
(-3585 1460);
DISPLAY 0.489362 (-3585 1460);
PAINT MONO (-3585 1460);
FORCEPROP 0 LASTPIN (-3375 1250) $PN G
J 0
(-3365 1260);
DISPLAY 0.489362 (-3365 1260);
PAINT MONO (-3365 1260);
FORCEPROP 0 LASTPIN (-3575 1150) $PN S
R 1
J 2
(-3585 1140);
DISPLAY 0.489362 (-3585 1140);
PAINT MONO (-3585 1140);
FORCEPROP 2 LAST PART_TYPE SMLF
J 2
(-3650 1475);
DISPLAY 1.021277 (-3650 1475);
FORCEPROP 1 LAST MATERIAL IC
J 2
(-3651 1200);
DISPLAY 0.489362 (-3651 1200);
PAINT SKYBLUE (-3651 1200);
FORCEPROP 2 LAST VALUE NX138BK
J 2
(-3650 1425);
DISPLAY 0.489362 (-3650 1425);
PAINT SKYBLUE (-3650 1425);
FORCEPROP 1 LAST PART_NUMBER BAM01380023
J 2
(-3651 1280);
DISPLAY 0.489362 (-3651 1280);
PAINT SKYBLUE (-3651 1280);
FORCEPROP 1 LAST NEEDS_NO_SIZE TRUE
J 2
(-3550 1300);
DISPLAY 0.468085 (-3550 1300);
PAINT GREEN (-3550 1300);
DISPLAY INVISIBLE (-3550 1300);
FORCEPROP 1 LAST CDS_LMAN_SYM_OUTLINE -100,100,100,-100
J 2
(-3550 1300);
DISPLAY 0.468085 (-3550 1300);
PAINT GREEN (-3550 1300);
DISPLAY INVISIBLE (-3550 1300);
FORCEPROP 2 LAST CDS_LIB pure_quanta
J 2
(-3550 1300);
DISPLAY INVISIBLE (-3550 1300);
FORCEPROP 1 LAST PATH I80
J 2
(-3550 1300);
DISPLAY 0.723404 (-3550 1300);
PAINT GREEN (-3550 1300);
DISPLAY INVISIBLE (-3550 1300);
FORCEADD MOSFET_N_GSD..1
R 2
(-2525 925);
FORCEPROP 1 LAST LOCATION Q30
J 2
(-2626 970);
DISPLAY 0.489362 (-2626 970);
PAINT SKYBLUE (-2626 970);
FORCEPROP 0 LAST $SEC 1
J 0
(-2625 1150);
DISPLAY 0.680851 (-2625 1150);
PAINT MONO (-2625 1150);
DISPLAY INVISIBLE (-2625 1150);
FORCEPROP 0 LAST CDS_SEC 1
J 0
(-2625 1150);
DISPLAY 0.680851 (-2625 1150);
DISPLAY INVISIBLE (-2625 1150);
FORCEPROP 0 LASTPIN (-2550 1075) $PN D
R 1
J 0
(-2560 1085);
DISPLAY 0.489362 (-2560 1085);
PAINT MONO (-2560 1085);
FORCEPROP 0 LASTPIN (-2350 875) $PN G
J 0
(-2340 885);
DISPLAY 0.489362 (-2340 885);
PAINT MONO (-2340 885);
FORCEPROP 0 LASTPIN (-2550 775) $PN S
R 1
J 2
(-2560 765);
DISPLAY 0.489362 (-2560 765);
PAINT MONO (-2560 765);
FORCEPROP 2 LAST PART_TYPE SMLF
J 2
(-2625 1100);
DISPLAY 1.021277 (-2625 1100);
FORCEPROP 1 LAST MATERIAL IC
J 2
(-2626 825);
DISPLAY 0.489362 (-2626 825);
PAINT SKYBLUE (-2626 825);
FORCEPROP 2 LAST VALUE NX138BK
J 2
(-2625 1050);
DISPLAY 0.489362 (-2625 1050);
PAINT SKYBLUE (-2625 1050);
FORCEPROP 1 LAST PART_NUMBER BAM01380023
J 2
(-2626 905);
DISPLAY 0.489362 (-2626 905);
PAINT SKYBLUE (-2626 905);
FORCEPROP 2 LAST CDS_LIB pure_quanta
J 0
(-2525 925);
DISPLAY INVISIBLE (-2525 925);
FORCEPROP 1 LAST CDS_LMAN_SYM_OUTLINE -100,100,100,-100
J 2
(-2525 925);
DISPLAY 0.468085 (-2525 925);
PAINT GREEN (-2525 925);
DISPLAY INVISIBLE (-2525 925);
FORCEPROP 1 LAST NEEDS_NO_SIZE TRUE
J 2
(-2525 925);
DISPLAY 0.468085 (-2525 925);
PAINT GREEN (-2525 925);
DISPLAY INVISIBLE (-2525 925);
FORCEPROP 1 LAST PATH I81
J 2
(-2525 925);
DISPLAY 0.723404 (-2525 925);
PAINT GREEN (-2525 925);
DISPLAY INVISIBLE (-2525 925);
FORCEADD Q_RES..1
(-5550 1575);
FORCEPROP 1 LAST LOCATION R1444
J 0
(-5850 1575);
DISPLAY 0.489362 (-5850 1575);
PAINT SKYBLUE (-5850 1575);
FORCEPROP 0 LAST $SEC 1
J 0
(-5700 1625);
DISPLAY 0.680851 (-5700 1625);
PAINT MONO (-5700 1625);
DISPLAY INVISIBLE (-5700 1625);
FORCEPROP 0 LAST CDS_SEC 1
J 0
(-5700 1625);
DISPLAY 0.680851 (-5700 1625);
DISPLAY INVISIBLE (-5700 1625);
FORCEPROP 1 LASTPIN (-5650 1575) $PN 1
J 0
(-5638 1587);
DISPLAY 0.489362 (-5638 1587);
PAINT MONO (-5638 1587);
FORCEPROP 1 LASTPIN (-5450 1575) $PN 2
J 0
(-5488 1587);
DISPLAY 0.489362 (-5488 1587);
PAINT MONO (-5488 1587);
FORCEPROP 1 LAST WATTAGE 1/16W
J 2
(-5475 1500);
DISPLAY 0.489362 (-5475 1500);
PAINT SKYBLUE (-5475 1500);
FORCEPROP 1 LAST MATERIAL CHIP
J 0
(-5450 1500);
DISPLAY 0.489362 (-5450 1500);
PAINT SKYBLUE (-5450 1500);
FORCEPROP 1 LAST TOLERANCE 1%
J 0
(-5675 1500);
DISPLAY 0.489362 (-5675 1500);
PAINT SKYBLUE (-5675 1500);
FORCEPROP 1 LAST VALUE 200
J 2
(-5700 1500);
DISPLAY 0.489362 (-5700 1500);
PAINT SKYBLUE (-5700 1500);
FORCEPROP 1 LAST PART_NUMBER CS12002FB06
J 0
(-5650 1650);
DISPLAY 0.489362 (-5650 1650);
PAINT SKYBLUE (-5650 1650);
FORCEPROP 1 LAST PACK_TYPE 0402LF
J 0
(-5325 1500);
DISPLAY 0.489362 (-5325 1500);
PAINT SKYBLUE (-5325 1500);
FORCEPROP 2 LAST CDS_LIB pure_quanta
J 0
(-5550 1575);
DISPLAY INVISIBLE (-5550 1575);
FORCEPROP 1 LAST PATH I82
J 0
(-5600 1725);
DISPLAY 0.978723 (-5600 1725);
PAINT WHITE (-5600 1725);
DISPLAY INVISIBLE (-5600 1725);
FORCEADD UNIVERSAL_POWER..1
(-5925 1825);
FORCEPROP 3 LASTPIN (-5925 1775) SIG_NAME P3V3_STBY\g
J 0
(-5915 1785);
DISPLAY 0.659574 (-5915 1785);
PAINT MONO (-5915 1785);
DISPLAY INVISIBLE (-5915 1785);
FORCEPROP 1 LAST HDL_POWER P3V3_STBY
J 1
(-5925 1875);
DISPLAY 0.489362 (-5925 1875);
PAINT GREEN (-5925 1875);
FORCEPROP 2 LAST BOM_COST OCP3.0 
J 0
(-5925 1925);
DISPLAY 0.680851 (-5925 1925);
DISPLAY INVISIBLE (-5925 1925);
FORCEPROP 2 LAST CDS_LIB pure_quanta_power
J 0
(-5925 1825);
DISPLAY INVISIBLE (-5925 1825);
FORCEPROP 1 LAST PATH I83
J 0
(-5875 1850);
DISPLAY 0.872340 (-5875 1850);
PAINT AQUA (-5875 1850);
DISPLAY INVISIBLE (-5875 1850);
FORCEADD UNIVERSAL_GND..1
(-2550 625);
FORCEPROP 3 LASTPIN (-2550 675) SIG_NAME GND\g
J 0
(-2540 685);
DISPLAY 0.659574 (-2540 685);
PAINT MONO (-2540 685);
DISPLAY INVISIBLE (-2540 685);
FORCEPROP 1 LAST HDL_POWER GND
J 1
(-2525 550);
DISPLAY 0.489362 (-2525 550);
PAINT GREEN (-2525 550);
FORCEPROP 2 LAST BOM_COST MISC.
J 0
(-2525 600);
DISPLAY 0.680851 (-2525 600);
DISPLAY INVISIBLE (-2525 600);
FORCEPROP 2 LAST CDS_LIB pure_quanta_power
J 0
(-2550 625);
DISPLAY INVISIBLE (-2550 625);
FORCEPROP 1 LAST PATH I85
J 0
(-2475 625);
DISPLAY 0.872340 (-2475 625);
PAINT AQUA (-2475 625);
DISPLAY INVISIBLE (-2475 625);
FORCEADD UNIVERSAL_POWER..1
(-2550 1725);
FORCEPROP 3 LASTPIN (-2550 1675) SIG_NAME P3V3_STBY\g
J 0
(-2540 1685);
DISPLAY 0.659574 (-2540 1685);
PAINT MONO (-2540 1685);
DISPLAY INVISIBLE (-2540 1685);
FORCEPROP 1 LAST HDL_POWER P3V3_STBY
J 1
(-2550 1775);
DISPLAY 0.489362 (-2550 1775);
PAINT GREEN (-2550 1775);
FORCEPROP 2 LAST CDS_LIB pure_quanta_power
J 0
(-2550 1725);
DISPLAY INVISIBLE (-2550 1725);
FORCEPROP 1 LAST PATH I86
J 0
(-2500 1750);
DISPLAY 0.872340 (-2500 1750);
PAINT AQUA (-2500 1750);
DISPLAY INVISIBLE (-2500 1750);
FORCEADD Q_RES..2
(-2550 1500);
FORCEPROP 1 LAST LOCATION R1507
J 0
(-2505 1625);
DISPLAY 0.489362 (-2505 1625);
PAINT SKYBLUE (-2505 1625);
FORCEPROP 0 LAST $SEC 1
J 0
(-2500 1650);
DISPLAY 0.680851 (-2500 1650);
PAINT MONO (-2500 1650);
DISPLAY INVISIBLE (-2500 1650);
FORCEPROP 0 LAST CDS_SEC 1
J 0
(-2500 1650);
DISPLAY 0.680851 (-2500 1650);
DISPLAY INVISIBLE (-2500 1650);
FORCEPROP 1 LASTPIN (-2550 1600) $PN 1
J 0
(-2545 1562);
DISPLAY 0.489362 (-2545 1562);
PAINT MONO (-2545 1562);
FORCEPROP 1 LASTPIN (-2550 1400) $PN 2
J 0
(-2545 1410);
DISPLAY 0.489362 (-2545 1410);
PAINT MONO (-2545 1410);
FORCEPROP 1 LAST WATTAGE 1/16W
J 0
(-2510 1475);
DISPLAY 0.489362 (-2510 1475);
PAINT SKYBLUE (-2510 1475);
FORCEPROP 1 LAST MATERIAL CHIP
J 0
(-2510 1425);
DISPLAY 0.489362 (-2510 1425);
PAINT SKYBLUE (-2510 1425);
FORCEPROP 1 LAST TOLERANCE 5%
J 0
(-2505 1525);
DISPLAY 0.489362 (-2505 1525);
PAINT SKYBLUE (-2505 1525);
FORCEPROP 1 LAST VALUE 1K
J 0
(-2505 1575);
DISPLAY 0.489362 (-2505 1575);
PAINT SKYBLUE (-2505 1575);
FORCEPROP 1 LAST PACK_TYPE 0402LF
J 0
(-2510 1375);
DISPLAY 0.489362 (-2510 1375);
PAINT SKYBLUE (-2510 1375);
FORCEPROP 2 LAST CDS_LIB pure_quanta
J 0
(-2550 1500);
DISPLAY INVISIBLE (-2550 1500);
FORCEPROP 1 LAST PATH I87
J 0
(-2500 1675);
DISPLAY 0.978723 (-2500 1675);
PAINT WHITE (-2500 1675);
DISPLAY INVISIBLE (-2500 1675);
FORCEPROP 1 LAST PART_NUMBER TMP_QCS21002JB34
J 0
(-2510 1325);
DISPLAY 0.638298 (-2510 1325);
PAINT SKYBLUE (-2510 1325);
DISPLAY INVISIBLE (-2510 1325);
FORCEADD OFFPAGE..4
(-1600 875);
FORCEPROP 2 LAST $XR2 28 
J 0
(-1204 875);
DISPLAY 0.638298 (-1204 875);
PAINT MONO (-1204 875);
FORCEPROP 2 LAST $XR1 144 
J 0
(-1324 875);
DISPLAY 0.638298 (-1324 875);
PAINT MONO (-1324 875);
FORCEPROP 2 LAST $XR0 80 
J 0
(-1414 875);
DISPLAY 0.638298 (-1414 875);
PAINT MONO (-1414 875);
FORCEPROP 2 LAST PATH I88
J 0
(-1425 950);
DISPLAY 0.680851 (-1425 950);
DISPLAY INVISIBLE (-1425 950);
FORCEPROP 1 LAST COMMENT_BODY TRUE
J 0
(-1625 775);
DISPLAY 0.872340 (-1625 775);
PAINT GREEN (-1625 775);
DISPLAY INVISIBLE (-1625 775);
FORCEPROP 1 LAST OFFPAGE TRUE
J 0
(-1275 750);
DISPLAY 0.872340 (-1275 750);
PAINT GREEN (-1275 750);
DISPLAY INVISIBLE (-1275 750);
FORCEPROP 2 LAST CDS_LIB standard
J 0
(-1600 875);
DISPLAY INVISIBLE (-1600 875);
FORCEADD QUANTA_TITLE_BLOCK_C..1
(0 0);
FORCEPROP 0 LAST CDS_CON_LAST_MODIFIED Fri Mar 11 14:53:18 2022
J 0
(-1885 15);
DISPLAY INVISIBLE (-1885 15);
FORCEPROP 1 LAST CUSTOM_TXT_CDS <CON_LAST_MODIFIED>
J 0
(-1885 15);
DISPLAY 0.978723 (-1885 15);
FORCEPROP 2 LAST CUSTOM_TXT_CDS <XR_PAGE_TITLE>
J 0
(-7890 5250);
DISPLAY 0.638298 (-7890 5250);
PAINT PINK (-7890 5250);
DISPLAY INVISIBLE (-7890 5250);
FORCEPROP 1 LAST CUSTOM_TXT_CDS <NAME_2>
J 0
(-3175 50);
FORCEPROP 1 LAST CUSTOM_TXT_CDS <NAME_1>
J 0
(-3175 175);
FORCEPROP 1 LAST CUSTOM_TXT_CDS <Q_NUMBER>
J 0
(-1403 103);
DISPLAY 1.212766 (-1403 103);
FORCEPROP 1 LAST CUSTOM_TXT_CDS <Q_PROJ>
J 0
(-2382 102);
DISPLAY 1.212766 (-2382 102);
FORCEPROP 1 LAST CUSTOM_TXT_CDS <Q_REV>
J 0
(-184 103);
DISPLAY 1.212766 (-184 103);
FORCEPROP 1 LAST CUSTOM_TXT_CDS <CON_PAGE_NUM> OF <CON_TOTAL_PAGES>
J 0
(-446 18);
DISPLAY 0.978723 (-446 18);
FORCEPROP 1 LAST Q_TITLE LED (1/2)
J 0
(-9250 50);
DISPLAY 2.446809 (-9250 50);
PAINT GREEN (-9250 50);
FORCEPROP 1 LAST Q_DEPT BU9
J 1
(-3763 49);
DISPLAY 1.957447 (-3763 49);
PAINT GREEN (-3763 49);
FORCEPROP 2 LAST CDS_LIB pure_quanta
J 0
(0 0);
DISPLAY INVISIBLE (0 0);
FORCEPROP 1 LAST CDS_LMAN_SYM_OUTLINE -9475,6775,100,-125
J 0
(0 0);
DISPLAY 0.468085 (0 0);
PAINT GREEN (0 0);
DISPLAY INVISIBLE (0 0);
FORCEPROP 2 LAST PAGE_BORDER TRUE
J 0
(-7890 5250);
DISPLAY 0.638298 (-7890 5250);
PAINT PINK (-7890 5250);
DISPLAY INVISIBLE (-7890 5250);
FORCEPROP 1 LAST COMMENT_BODY TRUE
J 0
(12 -13);
DISPLAY 0.978723 (12 -13);
PAINT GREEN (12 -13);
DISPLAY INVISIBLE (12 -13);
FORCEPROP 2 LAST CDS_XR_PAGE_TITLE CR-142 : @T6G_MB_LIB.T6G(SCH_1):PAGE142
J 0
(-7890 5250);
DISPLAY 0.638298 (-7890 5250);
PAINT PINK (-7890 5250);
DISPLAY INVISIBLE (-7890 5250);
WIRE 16 -1 (-2550 1600)(-2550 1675);
WIRE 16 -1 (-2350 875)(-1650 875);
FORCEPROP 2 LAST SIG_NAME BIOS_DEBUG_MODE
J 0
(-2285 885);
DISPLAY 0.489362 (-2285 885);
WIRE 16 -1 (-2550 1400)(-2550 1250);
WIRE 16 -1 (-2550 1075)(-2550 1250);
WIRE 16 -1 (-2550 1250)(-3375 1250);
FORCEPROP 2 LAST SIG_NAME LED_BIOS_DBG_MODE_N
J 0
(-3285 1260);
DISPLAY 0.489362 (-3285 1260);
FORCEPROP 2 LASTPROP $XRERR UNIQUE?
J 0
(-3525 1260);
DISPLAY 0.638298 (-3525 1260);
PAINT MONO (-3525 1260);
DISPLAY INVISIBLE (-3525 1260);
WIRE 16 -1 (-3575 1450)(-3575 1575);
WIRE 16 -1 (-3575 1575)(-4500 1575);
FORCEPROP 2 LAST SIG_NAME LED_BIOS_DBG_MODE
J 0
(-4210 1585);
DISPLAY 0.489362 (-4210 1585);
FORCEPROP 2 LASTPROP $XRERR UNIQUE?
J 0
(-4450 1585);
DISPLAY 0.638298 (-4450 1585);
PAINT MONO (-4450 1585);
DISPLAY INVISIBLE (-4450 1585);
WIRE 16 -1 (-4800 1575)(-5450 1575);
FORCEPROP 2 LAST SIG_NAME LED_BIOS_DBG_MODE_R
J 0
(-5385 1585);
DISPLAY 0.489362 (-5385 1585);
FORCEPROP 2 LASTPROP $XRERR UNIQUE?
J 0
(-5625 1585);
DISPLAY 0.638298 (-5625 1585);
PAINT MONO (-5625 1585);
DISPLAY INVISIBLE (-5625 1585);
WIRE 16 -1 (-5925 1775)(-5925 1575);
WIRE 16 -1 (-5650 1575)(-5925 1575);
WIRE 16 -1 (-2550 725)(-3575 725);
WIRE 16 -1 (-2550 775)(-2550 725);
WIRE 16 -1 (-2550 725)(-2550 675);
WIRE 16 -1 (-3575 725)(-3575 1150);
DOT 1 (-2550 725);
DOT 1 (-2550 1250);
FORCENOTE
BIOS DBG MODE LED
(-2375 2000) 0;
DISPLAY LEFT (-2375 2000);
DISPLAY 2.000000 (-2375 2000);
QUIT
